(kicad_pcb
	(version 20241229)
	(generator "pcbnew")
	(generator_version "9.0")
	(general
		(thickness 1.599998)
		(legacy_teardrops no)
	)
	(paper "A4")
	(title_block
		(title "Artix - Datacenter Secure Control Module (DC-SCM)")
		(date "2024-11-06")
		(rev "1.1.3")
		(comment 9 "footprints 169-174 of 544")
	)
	(layers
		(0 "F.Cu" signal)
		(4 "In1.Cu" signal)
		(6 "In2.Cu" signal)
		(8 "In3.Cu" signal)
		(10 "In4.Cu" signal)
		(12 "In5.Cu" signal)
		(14 "In6.Cu" signal)
		(2 "B.Cu" signal)
		(9 "F.Adhes" user "F.Adhesive")
		(11 "B.Adhes" user "B.Adhesive")
		(13 "F.Paste" user)
		(15 "B.Paste" user)
		(5 "F.SilkS" user "F.Silkscreen")
		(7 "B.SilkS" user "B.Silkscreen")
		(1 "F.Mask" user)
		(3 "B.Mask" user)
		(17 "Dwgs.User" user "User.Drawings")
		(19 "Cmts.User" user "User.Comments")
		(21 "Eco1.User" user "User.Eco1")
		(23 "Eco2.User" user "User.Eco2")
		(25 "Edge.Cuts" user)
		(27 "Margin" user)
		(31 "F.CrtYd" user "F.Courtyard")
		(29 "B.CrtYd" user "B.Courtyard")
		(35 "F.Fab" user)
		(33 "B.Fab" user)
	)
	(footprint "antmicro-footprints:R_0402_1005Metric"
		(layer "F.Cu")
		(at 89.95 75.95)
		(descr "Resistor SMD 0402")
		(tags "resistor SMD 0402")
		(property "Reference" "R185"
			(at 0.95 0.35 0)
			(layer "F.SilkS")
			(effects
				(font
					(size 0.7 0.7)
					(thickness 0.15)
				)
				(justify left bottom)
			)
		)
		(property "Value" "R_0R_0402"
			(at 0 1.4 0)
			(layer "F.Fab")
			(effects
				(font
					(size 0.7 0.7)
					(thickness 0.15)
				)
				(justify left bottom)
			)
		)
		(property "Datasheet" "https://industrial.panasonic.com/cdbs/www-data/pdf/RDA0000/AOA0000C301.pdf"
			(at 0 0 0)
			(layer "F.Fab")
			(hide yes)
			(effects
				(font
					(size 1.27 1.27)
					(thickness 0.15)
				)
			)
		)
		(property "Description" "SMD Chip Resistor, Jumper, 0 ohm, 100 mW, 0402 [1005 Metric], Thick Film, General Purpose"
			(at 0 0 0)
			(layer "F.Fab")
			(hide yes)
			(effects
				(font
					(size 1.27 1.27)
					(thickness 0.15)
				)
			)
		)
		(property "Author" "Antmicro"
			(at 0 0 0)
			(layer "F.Fab")
			(hide yes)
			(effects
				(font
					(size 1 1)
					(thickness 0.15)
				)
			)
		)
		(property "Current" "1A"
			(at 0 0 0)
			(layer "F.Fab")
			(hide yes)
			(effects
				(font
					(size 1 1)
					(thickness 0.15)
				)
			)
		)
		(property "License" "Apache-2.0"
			(at 0 0 0)
			(layer "F.Fab")
			(hide yes)
			(effects
				(font
					(size 1 1)
					(thickness 0.15)
				)
			)
		)
		(property "MPN" "ERJ2GE0R00X"
			(at 0 0 0)
			(layer "F.Fab")
			(hide yes)
			(effects
				(font
					(size 1 1)
					(thickness 0.15)
				)
			)
		)
		(property "Manufacturer" "Panasonic"
			(at 0 0 0)
			(layer "F.Fab")
			(hide yes)
			(effects
				(font
					(size 1 1)
					(thickness 0.15)
				)
			)
		)
		(property "Tolerance" "~"
			(at 0 0 0)
			(layer "F.Fab")
			(hide yes)
			(effects
				(font
					(size 1 1)
					(thickness 0.15)
				)
			)
		)
		(property "Val" "0R"
			(at 0 0 0)
			(layer "F.Fab")
			(hide yes)
			(effects
				(font
					(size 1 1)
					(thickness 0.15)
				)
			)
		)
		(sheetname "/Power supply/")
		(sheetfile "power-supply.kicad_sch")
		(attr smd)
		(fp_rect
			(start -0.925 -0.47)
			(end 0.925 0.47)
			(stroke
				(width 0.05)
				(type default)
			)
			(fill no)
			(layer "F.CrtYd")
		)
		(fp_rect
			(start -0.5 -0.25)
			(end 0.5 0.25)
			(stroke
				(width 0.15)
				(type solid)
			)
			(fill no)
			(layer "F.Fab")
		)
		(pad "1" smd roundrect
			(at -0.48 0)
			(size 0.59 0.64)
			(layers "F.Cu" "F.Mask" "F.Paste")
			(roundrect_rratio 0.25)
			(net 347 "Net-(U16-EN)")
			(pintype "passive")
		)
		(pad "2" smd roundrect
			(at 0.48 0)
			(size 0.59 0.64)
			(layers "F.Cu" "F.Mask" "F.Paste")
			(roundrect_rratio 0.25)
			(net 297 "/Power supply/VCCIO_EN")
			(pintype "passive")
		)
	)
	(footprint "antmicro-footprints:R_0402_1005Metric"
		(layer "F.Cu")
		(at 90.525 74.4 -90)
		(descr "Resistor SMD 0402")
		(tags "resistor SMD 0402")
		(property "Reference" "R186"
			(at -1.8 -3.475 90)
			(layer "F.SilkS")
			(effects
				(font
					(size 0.7 0.7)
					(thickness 0.15)
				)
				(justify right bottom)
			)
		)
		(property "Value" "R_100k_0402"
			(at 0 1.4 90)
			(layer "F.Fab")
			(effects
				(font
					(size 0.7 0.7)
					(thickness 0.15)
				)
				(justify right bottom)
			)
		)
		(property "Datasheet" "https://www.bourns.com/docs/product-datasheets/cr.pdf"
			(at 0 0 270)
			(layer "F.Fab")
			(hide yes)
			(effects
				(font
					(size 1.27 1.27)
					(thickness 0.15)
				)
			)
		)
		(property "Description" "SMD Chip Resistor, 100 kohm, ± 1%, 62.5 mW, 0402 [1005 Metric], Thick Film, General Purpose"
			(at 0 0 270)
			(layer "F.Fab")
			(hide yes)
			(effects
				(font
					(size 1.27 1.27)
					(thickness 0.15)
				)
			)
		)
		(property "Author" "Antmicro"
			(at 16.125 164.925 0)
			(layer "F.Fab")
			(hide yes)
			(effects
				(font
					(size 1 1)
					(thickness 0.15)
				)
			)
		)
		(property "License" "Apache-2.0"
			(at 16.125 164.925 0)
			(layer "F.Fab")
			(hide yes)
			(effects
				(font
					(size 1 1)
					(thickness 0.15)
				)
			)
		)
		(property "MPN" "CR0402-FX-1003GLF"
			(at 16.125 164.925 0)
			(layer "F.Fab")
			(hide yes)
			(effects
				(font
					(size 1 1)
					(thickness 0.15)
				)
			)
		)
		(property "Manufacturer" "Bourns"
			(at 16.125 164.925 0)
			(layer "F.Fab")
			(hide yes)
			(effects
				(font
					(size 1 1)
					(thickness 0.15)
				)
			)
		)
		(property "Tolerance" "1%"
			(at 16.125 164.925 0)
			(layer "F.Fab")
			(hide yes)
			(effects
				(font
					(size 1 1)
					(thickness 0.15)
				)
			)
		)
		(property "Val" "100k"
			(at 16.125 164.925 0)
			(layer "F.Fab")
			(hide yes)
			(effects
				(font
					(size 1 1)
					(thickness 0.15)
				)
			)
		)
		(sheetname "/Power supply/")
		(sheetfile "power-supply.kicad_sch")
		(attr smd)
		(fp_rect
			(start -0.925 -0.47)
			(end 0.925 0.47)
			(stroke
				(width 0.05)
				(type default)
			)
			(fill no)
			(layer "F.CrtYd")
		)
		(fp_rect
			(start -0.5 -0.25)
			(end 0.5 0.25)
			(stroke
				(width 0.15)
				(type solid)
			)
			(fill no)
			(layer "F.Fab")
		)
		(pad "1" smd roundrect
			(at -0.48 0 270)
			(size 0.59 0.64)
			(layers "F.Cu" "F.Mask" "F.Paste")
			(roundrect_rratio 0.25)
			(net 60 "Net-(C101-Pad2)")
			(pintype "passive")
		)
		(pad "2" smd roundrect
			(at 0.48 0 270)
			(size 0.59 0.64)
			(layers "F.Cu" "F.Mask" "F.Paste")
			(roundrect_rratio 0.25)
			(net 10 "Net-(U16-FB)")
			(pintype "passive")
		)
	)
	(footprint "antmicro-footprints:C_0603_1608Metric"
		(layer "F.Cu")
		(at 85 74.35 -90)
		(descr "Capacitor SMD 0603")
		(tags "capacitor 0603")
		(property "Reference" "C2"
			(at 1.45 0.5 270)
			(layer "F.SilkS")
			(effects
				(font
					(size 0.7 0.7)
					(thickness 0.15)
				)
				(justify left bottom)
			)
		)
		(property "Value" "C_10u_0603"
			(at 0 1.6 270)
			(layer "F.Fab")
			(effects
				(font
					(size 0.7 0.7)
					(thickness 0.15)
				)
				(justify left bottom)
			)
		)
		(property "Datasheet" "https://www.murata.com/products/productdetail?partno=GRM188R61A106KE69%23"
			(at 0 0 270)
			(layer "F.Fab")
			(hide yes)
			(effects
				(font
					(size 1.27 1.27)
					(thickness 0.15)
				)
			)
		)
		(property "Description" "SMD Multilayer Ceramic Capacitor, 10 µF, 10 V, 0603 [1608 Metric], ± 10%, X5R, GRM Series"
			(at 0 0 270)
			(layer "F.Fab")
			(hide yes)
			(effects
				(font
					(size 1.27 1.27)
					(thickness 0.15)
				)
			)
		)
		(property "Author" "Antmicro"
			(at 10.65 159.35 0)
			(layer "F.Fab")
			(hide yes)
			(effects
				(font
					(size 1 1)
					(thickness 0.15)
				)
			)
		)
		(property "Dielectric" "template_dielectric"
			(at 10.65 159.35 0)
			(layer "F.Fab")
			(hide yes)
			(effects
				(font
					(size 1 1)
					(thickness 0.15)
				)
			)
		)
		(property "License" "Apache-2.0"
			(at 10.65 159.35 0)
			(layer "F.Fab")
			(hide yes)
			(effects
				(font
					(size 1 1)
					(thickness 0.15)
				)
			)
		)
		(property "MPN" "GRM188R61A106KE69D"
			(at 10.65 159.35 0)
			(layer "F.Fab")
			(hide yes)
			(effects
				(font
					(size 1 1)
					(thickness 0.15)
				)
			)
		)
		(property "Manufacturer" "Murata"
			(at 10.65 159.35 0)
			(layer "F.Fab")
			(hide yes)
			(effects
				(font
					(size 1 1)
					(thickness 0.15)
				)
			)
		)
		(property "Val" "10u"
			(at 10.65 159.35 0)
			(layer "F.Fab")
			(hide yes)
			(effects
				(font
					(size 1 1)
					(thickness 0.15)
				)
			)
		)
		(property "Voltage" ""
			(at 10.65 159.35 0)
			(layer "F.Fab")
			(hide yes)
			(effects
				(font
					(size 1 1)
					(thickness 0.15)
				)
			)
		)
		(sheetname "/Power supply/")
		(sheetfile "power-supply.kicad_sch")
		(attr smd)
		(fp_line
			(start -0.15 0.4)
			(end 0.15 0.4)
			(stroke
				(width 0.15)
				(type solid)
			)
			(layer "F.SilkS")
		)
		(fp_line
			(start -0.15 -0.4)
			(end 0.15 -0.4)
			(stroke
				(width 0.15)
				(type solid)
			)
			(layer "F.SilkS")
		)
		(fp_rect
			(start -1.25 -0.65)
			(end 1.25 0.65)
			(stroke
				(width 0.05)
				(type solid)
			)
			(fill no)
			(layer "F.CrtYd")
		)
		(fp_rect
			(start -0.8 -0.4)
			(end 0.8 0.4)
			(stroke
				(width 0.15)
				(type solid)
			)
			(fill no)
			(layer "F.Fab")
		)
		(pad "1" smd roundrect
			(at -0.7 0 270)
			(size 0.8 1)
			(layers "F.Cu" "F.Mask" "F.Paste")
			(roundrect_rratio 0.2)
			(net 1 "GND")
			(pintype "passive")
		)
		(pad "2" smd roundrect
			(at 0.7 0 270)
			(size 0.8 1)
			(layers "F.Cu" "F.Mask" "F.Paste")
			(roundrect_rratio 0.2)
			(net 4 "VCC5V0")
			(pintype "passive")
		)
	)
	(footprint "antmicro-footprints:R_0402_1005Metric"
		(layer "F.Cu")
		(at 73.515 165.865 90)
		(descr "Resistor SMD 0402")
		(tags "resistor SMD 0402")
		(property "Reference" "R53"
			(at -0.935 -1.515 90)
			(layer "F.SilkS")
			(effects
				(font
					(size 0.7 0.7)
					(thickness 0.15)
				)
				(justify left bottom)
			)
		)
		(property "Value" "R_200k_0402"
			(at 0 1.4 90)
			(layer "F.Fab")
			(effects
				(font
					(size 0.7 0.7)
					(thickness 0.15)
				)
				(justify left bottom)
			)
		)
		(property "Datasheet" "https://www.bourns.com/docs/product-datasheets/cr.pdf"
			(at 0 0 90)
			(layer "F.Fab")
			(hide yes)
			(effects
				(font
					(size 1.27 1.27)
					(thickness 0.15)
				)
			)
		)
		(property "Description" "SMD Chip Resistor, 200 kohm, ± 1%, 62.5 mW, 0402 [1005 Metric], Thick Film, General Purpose"
			(at 0 0 90)
			(layer "F.Fab")
			(hide yes)
			(effects
				(font
					(size 1.27 1.27)
					(thickness 0.15)
				)
			)
		)
		(property "Author" "Antmicro"
			(at 239.38 92.35 0)
			(layer "F.Fab")
			(hide yes)
			(effects
				(font
					(size 1 1)
					(thickness 0.15)
				)
			)
		)
		(property "License" "Apache-2.0"
			(at 239.38 92.35 0)
			(layer "F.Fab")
			(hide yes)
			(effects
				(font
					(size 1 1)
					(thickness 0.15)
				)
			)
		)
		(property "MPN" "CR0402-FX-2003GLF"
			(at 239.38 92.35 0)
			(layer "F.Fab")
			(hide yes)
			(effects
				(font
					(size 1 1)
					(thickness 0.15)
				)
			)
		)
		(property "Manufacturer" "Bourns"
			(at 239.38 92.35 0)
			(layer "F.Fab")
			(hide yes)
			(effects
				(font
					(size 1 1)
					(thickness 0.15)
				)
			)
		)
		(property "Tolerance" "1%"
			(at 239.38 92.35 0)
			(layer "F.Fab")
			(hide yes)
			(effects
				(font
					(size 1 1)
					(thickness 0.15)
				)
			)
		)
		(property "Val" "200k"
			(at 239.38 92.35 0)
			(layer "F.Fab")
			(hide yes)
			(effects
				(font
					(size 1 1)
					(thickness 0.15)
				)
			)
		)
		(sheetname "/Interfaces/")
		(sheetfile "interfaces.kicad_sch")
		(attr smd)
		(fp_rect
			(start -0.925 -0.47)
			(end 0.925 0.47)
			(stroke
				(width 0.05)
				(type default)
			)
			(fill no)
			(layer "F.CrtYd")
		)
		(fp_rect
			(start -0.5 -0.25)
			(end 0.5 0.25)
			(stroke
				(width 0.15)
				(type solid)
			)
			(fill no)
			(layer "F.Fab")
		)
		(pad "1" smd roundrect
			(at -0.48 0 90)
			(size 0.59 0.64)
			(layers "F.Cu" "F.Mask" "F.Paste")
			(roundrect_rratio 0.25)
			(net 538 "1V0_PG")
			(pintype "passive")
		)
		(pad "2" smd roundrect
			(at 0.48 0 90)
			(size 0.59 0.64)
			(layers "F.Cu" "F.Mask" "F.Paste")
			(roundrect_rratio 0.25)
			(net 7 "/Interfaces/1V0_EN")
			(pintype "passive")
		)
	)
	(footprint "antmicro-footprints:C_0402_1005Metric"
		(layer "F.Cu")
		(at 74.515 165.865 90)
		(descr "Capacitor SMD 0402")
		(tags "capacitor SMD 0402")
		(property "Reference" "C39"
			(at -0.934 -1.515 90)
			(layer "F.SilkS")
			(effects
				(font
					(size 0.7 0.7)
					(thickness 0.15)
				)
				(justify left bottom)
			)
		)
		(property "Value" "C_100n_6V3_0402"
			(at 0 1.4 90)
			(layer "F.Fab")
			(effects
				(font
					(size 0.7 0.7)
					(thickness 0.15)
				)
				(justify left bottom)
			)
		)
		(property "Datasheet" "https://www.passivecomponent.com/wp-content/uploads/datasheet/WTC_MLCC_General_Purpose.pdf"
			(at 0 0 90)
			(layer "F.Fab")
			(hide yes)
			(effects
				(font
					(size 1.27 1.27)
					(thickness 0.15)
				)
			)
		)
		(property "Description" "SMT Multilayer Ceramic Capacitor, 0.1 µF, 6.3 V, 0402 [1005 Metric], ± 10%, X5R, Walsin MLCC"
			(at 0 0 90)
			(layer "F.Fab")
			(hide yes)
			(effects
				(font
					(size 1.27 1.27)
					(thickness 0.15)
				)
			)
		)
		(property "Author" "Antmicro"
			(at 240.38 91.35 0)
			(layer "F.Fab")
			(hide yes)
			(effects
				(font
					(size 1 1)
					(thickness 0.15)
				)
			)
		)
		(property "Dielectric" ""
			(at 240.38 91.35 0)
			(layer "F.Fab")
			(hide yes)
			(effects
				(font
					(size 1 1)
					(thickness 0.15)
				)
			)
		)
		(property "License" "Apache-2.0"
			(at 240.38 91.35 0)
			(layer "F.Fab")
			(hide yes)
			(effects
				(font
					(size 1 1)
					(thickness 0.15)
				)
			)
		)
		(property "MPN" "0402X104K6R3CT"
			(at 240.38 91.35 0)
			(layer "F.Fab")
			(hide yes)
			(effects
				(font
					(size 1 1)
					(thickness 0.15)
				)
			)
		)
		(property "Manufacturer" "Walsin"
			(at 240.38 91.35 0)
			(layer "F.Fab")
			(hide yes)
			(effects
				(font
					(size 1 1)
					(thickness 0.15)
				)
			)
		)
		(property "Public" "False"
			(at 240.38 91.35 0)
			(layer "F.Fab")
			(hide yes)
			(effects
				(font
					(size 1 1)
					(thickness 0.15)
				)
			)
		)
		(property "Val" "100n"
			(at 240.38 91.35 0)
			(layer "F.Fab")
			(hide yes)
			(effects
				(font
					(size 1 1)
					(thickness 0.15)
				)
			)
		)
		(property "Voltage" ""
			(at 240.38 91.35 0)
			(layer "F.Fab")
			(hide yes)
			(effects
				(font
					(size 1 1)
					(thickness 0.15)
				)
			)
		)
		(sheetname "/Interfaces/")
		(sheetfile "interfaces.kicad_sch")
		(attr smd)
		(fp_rect
			(start -0.925 -0.47)
			(end 0.925 0.47)
			(stroke
				(width 0.05)
				(type default)
			)
			(fill no)
			(layer "F.CrtYd")
		)
		(fp_line
			(start 0.504 -0.25)
			(end 0.504 0.248)
			(stroke
				(width 0.15)
				(type solid)
			)
			(layer "F.Fab")
		)
		(fp_line
			(start -0.494 -0.25)
			(end 0.504 -0.25)
			(stroke
				(width 0.15)
				(type solid)
			)
			(layer "F.Fab")
		)
		(fp_line
			(start 0.504 0.248)
			(end -0.494 0.248)
			(stroke
				(width 0.15)
				(type solid)
			)
			(layer "F.Fab")
		)
		(fp_line
			(start -0.494 0.248)
			(end -0.494 -0.25)
			(stroke
				(width 0.15)
				(type solid)
			)
			(layer "F.Fab")
		)
		(pad "1" smd roundrect
			(at -0.48 0 90)
			(size 0.59 0.64)
			(layers "F.Cu" "F.Mask" "F.Paste")
			(roundrect_rratio 0.25)
			(net 1 "GND")
			(pintype "passive")
		)
		(pad "2" smd roundrect
			(at 0.48 0 90)
			(size 0.59 0.64)
			(layers "F.Cu" "F.Mask" "F.Paste")
			(roundrect_rratio 0.25)
			(net 7 "/Interfaces/1V0_EN")
			(pintype "passive")
		)
	)
	(footprint "antmicro-footprints:C_0603_1608Metric"
		(layer "F.Cu")
		(at 82.565 68.8 -90)
		(descr "Capacitor SMD 0603")
		(tags "capacitor 0603")
		(property "Reference" "C74"
			(at -1.625 17.154 90)
			(layer "F.SilkS")
			(effects
				(font
					(size 0.7 0.7)
					(thickness 0.15)
				)
				(justify right bottom)
			)
		)
		(property "Value" "C_47u_0603"
			(at 0 1.6 90)
			(layer "F.Fab")
			(effects
				(font
					(size 0.7 0.7)
					(thickness 0.15)
				)
				(justify right bottom)
			)
		)
		(property "Datasheet" "https://www.murata.com/products/productdetail?partno=GRM188R60J476ME15%23"
			(at 0 0 270)
			(layer "F.Fab")
			(hide yes)
			(effects
				(font
					(size 1.27 1.27)
					(thickness 0.15)
				)
			)
		)
		(property "Description" "SMD Multilayer Ceramic Capacitor, 47 µF, 6.3 V, 0603 [1608 Metric], ± 20%, X5R, GRM Series"
			(at 0 0 270)
			(layer "F.Fab")
			(hide yes)
			(effects
				(font
					(size 1.27 1.27)
					(thickness 0.15)
				)
			)
		)
		(property "Author" "Antmicro"
			(at 13.765 151.365 0)
			(layer "F.Fab")
			(hide yes)
			(effects
				(font
					(size 1 1)
					(thickness 0.15)
				)
			)
		)
		(property "Dielectric" ""
			(at 13.765 151.365 0)
			(layer "F.Fab")
			(hide yes)
			(effects
				(font
					(size 1 1)
					(thickness 0.15)
				)
			)
		)
		(property "License" "Apache-2.0"
			(at 13.765 151.365 0)
			(layer "F.Fab")
			(hide yes)
			(effects
				(font
					(size 1 1)
					(thickness 0.15)
				)
			)
		)
		(property "MPN" "GRM188R60J476ME15D"
			(at 13.765 151.365 0)
			(layer "F.Fab")
			(hide yes)
			(effects
				(font
					(size 1 1)
					(thickness 0.15)
				)
			)
		)
		(property "Manufacturer" "Murata"
			(at 13.765 151.365 0)
			(layer "F.Fab")
			(hide yes)
			(effects
				(font
					(size 1 1)
					(thickness 0.15)
				)
			)
		)
		(property "Val" "47u"
			(at 13.765 151.365 0)
			(layer "F.Fab")
			(hide yes)
			(effects
				(font
					(size 1 1)
					(thickness 0.15)
				)
			)
		)
		(property "Voltage" ""
			(at 13.765 151.365 0)
			(layer "F.Fab")
			(hide yes)
			(effects
				(font
					(size 1 1)
					(thickness 0.15)
				)
			)
		)
		(sheetname "/Power supply/")
		(sheetfile "power-supply.kicad_sch")
		(attr smd)
		(fp_line
			(start -0.15 0.4)
			(end 0.15 0.4)
			(stroke
				(width 0.15)
				(type solid)
			)
			(layer "F.SilkS")
		)
		(fp_line
			(start -0.15 -0.4)
			(end 0.15 -0.4)
			(stroke
				(width 0.15)
				(type solid)
			)
			(layer "F.SilkS")
		)
		(fp_rect
			(start -1.25 -0.65)
			(end 1.25 0.65)
			(stroke
				(width 0.05)
				(type solid)
			)
			(fill no)
			(layer "F.CrtYd")
		)
		(fp_rect
			(start -0.8 -0.4)
			(end 0.8 0.4)
			(stroke
				(width 0.15)
				(type solid)
			)
			(fill no)
			(layer "F.Fab")
		)
		(pad "1" smd roundrect
			(at -0.7 0 270)
			(size 0.8 1)
			(layers "F.Cu" "F.Mask" "F.Paste")
			(roundrect_rratio 0.2)
			(net 1 "GND")
			(pintype "passive")
		)
		(pad "2" smd roundrect
			(at 0.7 0 270)
			(size 0.8 1)
			(layers "F.Cu" "F.Mask" "F.Paste")
			(roundrect_rratio 0.2)
			(net 114 "Net-(C72-Pad2)")
			(pintype "passive")
		)
	)
)
